# BASEBOARD_FAB2 (Tioga Pass) — schematic netlist excerpt (pin names and nets, part order shuffled) for the footprints in the layout excerpt that follows; sources: Cadence DE-HDL packaged netlist, KiCad conversion of Wiwynn_Tioga_Pass_MB.brd

R9P2  RES  49.9 1% CHIP  pkg 0402  page 206 : A = PVCCIO_CPU1 ; B = SVID_CLK0_CPU1_R
C2M12  CAP_A  22.0UF 4V 20% X6S  pkg 0603V  page 131 : A = P1V05_PCH_STBY ; B = GND
R6L10  RES  0.0 5% CHIP  pkg 0402  page 222 : A = PVDDQ_DEF ; B = VSENSE_PVDDQ_DEF_VTT

(kicad_pcb
	(version 20260206)
	(generator "pcbnew")
	(generator_version "10.0")
	(general
		(thickness 1.6)
		(legacy_teardrops no)
	)
	(paper "A4")
	(title_block
		(title "Wiwynn_Tioga_Pass_MB.brd")
		(comment 1 "Tioga Pass / footprints 3165-3167 of 4770")
	)
	(layers
		(0 "F.Cu" signal "TOP")
		(4 "In1.Cu" signal "L2GND")
		(6 "In2.Cu" signal "L3")
		(8 "In3.Cu" signal "L4GND")
		(10 "In4.Cu" signal "L5")
		(12 "In5.Cu" signal "L6GND")
		(14 "In6.Cu" signal "L7VCC")
		(16 "In7.Cu" signal "L8VCC")
		(18 "In8.Cu" signal "L9GND")
		(20 "In9.Cu" signal "L10")
		(22 "In10.Cu" signal "L11GND")
		(24 "In11.Cu" signal "L12")
		(26 "In12.Cu" signal "L13GND")
		(2 "B.Cu" signal "BOTTOM")
		(9 "F.Adhes" user "F.Adhesive")
		(11 "B.Adhes" user "B.Adhesive")
		(13 "F.Paste" user "Package Geometry/Pastemask Top")
		(15 "B.Paste" user "Package Geometry/Pastemask Bottom")
		(5 "F.SilkS" user "Ref Des/Silkscreen Top")
		(7 "B.SilkS" user "Ref Des/Silkscreen Bottom")
		(1 "F.Mask" user "Board Geometry/Soldermask Top")
		(3 "B.Mask" user "Board Geometry/Soldermask Bottom")
		(17 "Dwgs.User" user "User.Drawings")
		(19 "Cmts.User" user "User.Comments")
		(21 "Eco1.User" user "User.Eco1")
		(23 "Eco2.User" user "User.Eco2")
		(25 "Edge.Cuts" user "Board Geometry/Outline")
		(27 "Margin" user)
		(31 "F.CrtYd" user "Package Geometry/Place Bound Top")
		(29 "B.CrtYd" user "Package Geometry/Place Bound Bottom")
		(35 "F.Fab" user "Ref Des/Assembly Top")
		(33 "B.Fab" user "Ref Des/Assembly Bottom")
	)
	(footprint ""
		(layer "B.Cu")
		(at 405.257 -116.7765 180)
		(property "Reference" "C2M12"
			(at 0 0 0)
			(layer "B.SilkS")
			(hide yes)
			(effects
				(font
					(size 1.27 1.27)
				)
				(justify mirror)
			)
		)
		(property "Value" ""
			(at 0 0 0)
			(layer "B.Fab")
			(effects
				(font
					(size 1.27 1.27)
				)
				(justify mirror)
			)
		)
		(duplicate_pad_numbers_are_jumpers no)
		(fp_poly
			(pts
				(xy 0.4953 -0.2032) (xy -0.4953 -0.2032) (xy -0.4953 1.6002) (xy 0.4953 1.6002)
			)
			(stroke
				(width 0)
				(type default)
			)
			(fill no)
			(layer "B.CrtYd")
		)
		(fp_line
			(start 0.4953 1.6002)
			(end 0.4953 -0.2032)
			(stroke
				(width 0.1)
				(type default)
			)
			(layer "B.Fab")
		)
		(fp_line
			(start 0.4953 -0.2032)
			(end -0.4953 -0.2032)
			(stroke
				(width 0.1)
				(type default)
			)
			(layer "B.Fab")
		)
		(fp_line
			(start -0.4953 1.6002)
			(end 0.4953 1.6002)
			(stroke
				(width 0.1)
				(type default)
			)
			(layer "B.Fab")
		)
		(fp_line
			(start -0.4953 -0.2032)
			(end -0.4953 1.6002)
			(stroke
				(width 0.1)
				(type default)
			)
			(layer "B.Fab")
		)
		(pad "1" smd rect
			(at 0 0)
			(size 0.762 0.889)
			(layers "B.Cu" "B.Mask" "B.Paste")
			(net "P1V05_PCH_STBY")
		)
		(pad "2" smd rect
			(at 0 1.397)
			(size 0.762 0.889)
			(layers "B.Cu" "B.Mask" "B.Paste")
			(net "GND")
		)
		(zone
			(layer "B.Cu")
			(hatch none 0.5)
			(connect_pads
				(clearance 0)
			)
			(min_thickness 0.25)
			(keepout
				(tracks not_allowed)
				(vias allowed)
				(pads allowed)
				(copperpour not_allowed)
				(footprints allowed)
			)
			(placement
				(enabled no)
				(sheetname "")
			)
			(fill
				(thermal_gap 0.5)
				(thermal_bridge_width 0.5)
				(island_removal_mode 0)
			)
			(polygon
				(pts
					(xy 404.876 -117.221) (xy 405.638 -117.221) (xy 405.638 -117.729) (xy 404.876 -117.729)
				)
			)
		)
	)
	(footprint ""
		(layer "B.Cu")
		(at 17.526 -87.7062)
		(property "Reference" "R9P2"
			(at 0 0 0)
			(layer "B.SilkS")
			(hide yes)
			(effects
				(font
					(size 1.27 1.27)
				)
				(justify mirror)
			)
		)
		(property "Value" ""
			(at 0 0 0)
			(layer "B.Fab")
			(effects
				(font
					(size 1.27 1.27)
				)
				(justify mirror)
			)
		)
		(duplicate_pad_numbers_are_jumpers no)
		(fp_poly
			(pts
				(xy 0.2794 -0.1016) (xy -0.2794 -0.1016) (xy -0.2794 0.9906) (xy 0.2794 0.9906)
			)
			(stroke
				(width 0)
				(type default)
			)
			(fill no)
			(layer "B.CrtYd")
		)
		(fp_line
			(start -0.2794 -0.1016)
			(end 0.2794 -0.1016)
			(stroke
				(width 0.1)
				(type default)
			)
			(layer "B.Fab")
		)
		(fp_line
			(start -0.2794 0.9906)
			(end -0.2794 -0.1016)
			(stroke
				(width 0.1)
				(type default)
			)
			(layer "B.Fab")
		)
		(fp_line
			(start 0.2794 -0.1016)
			(end 0.2794 0.9906)
			(stroke
				(width 0.1)
				(type default)
			)
			(layer "B.Fab")
		)
		(fp_line
			(start 0.2794 0.9906)
			(end -0.2794 0.9906)
			(stroke
				(width 0.1)
				(type default)
			)
			(layer "B.Fab")
		)
		(pad "1" smd rect
			(at 0 0 180)
			(size 0.508 0.508)
			(layers "B.Cu" "B.Mask" "B.Paste")
			(net "PVCCIO_CPU1")
		)
		(pad "2" smd rect
			(at 0 0.889 180)
			(size 0.508 0.508)
			(layers "B.Cu" "B.Mask" "B.Paste")
			(net "SVID_CLK0_CPU1_R")
		)
		(zone
			(layer "B.Cu")
			(hatch none 0.5)
			(connect_pads
				(clearance 0)
			)
			(min_thickness 0.25)
			(keepout
				(tracks allowed)
				(vias not_allowed)
				(pads allowed)
				(copperpour not_allowed)
				(footprints allowed)
			)
			(placement
				(enabled no)
				(sheetname "")
			)
			(fill
				(thermal_gap 0.5)
				(thermal_bridge_width 0.5)
				(island_removal_mode 0)
			)
			(polygon
				(pts
					(xy 17.78 -87.4522) (xy 17.272 -87.4522) (xy 17.272 -87.0712) (xy 17.78 -87.0712)
				)
			)
		)
		(zone
			(layer "B.Cu")
			(hatch none 0.5)
			(connect_pads
				(clearance 0)
			)
			(min_thickness 0.25)
			(keepout
				(tracks not_allowed)
				(vias allowed)
				(pads allowed)
				(copperpour not_allowed)
				(footprints allowed)
			)
			(placement
				(enabled no)
				(sheetname "")
			)
			(fill
				(thermal_gap 0.5)
				(thermal_bridge_width 0.5)
				(island_removal_mode 0)
			)
			(polygon
				(pts
					(xy 17.78 -87.0712) (xy 17.272 -87.0712) (xy 17.272 -87.4522) (xy 17.78 -87.4522)
				)
			)
		)
	)
	(footprint ""
		(layer "B.Cu")
		(at 183.515 -145.796 180)
		(property "Reference" "R6L10"
			(at 0 0 0)
			(layer "B.SilkS")
			(hide yes)
			(effects
				(font
					(size 1.27 1.27)
				)
				(justify mirror)
			)
		)
		(property "Value" ""
			(at 0 0 0)
			(layer "B.Fab")
			(effects
				(font
					(size 1.27 1.27)
				)
				(justify mirror)
			)
		)
		(duplicate_pad_numbers_are_jumpers no)
		(fp_rect
			(start 0.2794 0.9906)
			(end -0.2794 -0.1016)
			(stroke
				(width 0)
				(type default)
			)
			(fill no)
			(layer "B.CrtYd")
		)
		(fp_line
			(start 0.2794 0.9906)
			(end -0.2794 0.9906)
			(stroke
				(width 0.1)
				(type default)
			)
			(layer "B.Fab")
		)
		(fp_line
			(start 0.2794 -0.1016)
			(end 0.2794 0.9906)
			(stroke
				(width 0.1)
				(type default)
			)
			(layer "B.Fab")
		)
		(fp_line
			(start -0.2794 0.9906)
			(end -0.2794 -0.1016)
			(stroke
				(width 0.1)
				(type default)
			)
			(layer "B.Fab")
		)
		(fp_line
			(start -0.2794 -0.1016)
			(end 0.2794 -0.1016)
			(stroke
				(width 0.1)
				(type default)
			)
			(layer "B.Fab")
		)
		(pad "1" smd rect
			(at 0 0)
			(size 0.508 0.508)
			(layers "B.Cu" "B.Mask" "B.Paste")
			(net "PVDDQ_DEF")
		)
		(pad "2" smd rect
			(at 0 0.889)
			(size 0.508 0.508)
			(layers "B.Cu" "B.Mask" "B.Paste")
			(net "VSENSE_PVDDQ_DEF_VTT")
		)
		(zone
			(layer "B.Cu")
			(hatch none 0.5)
			(connect_pads
				(clearance 0)
			)
			(min_thickness 0.25)
			(keepout
				(tracks not_allowed)
				(vias allowed)
				(pads allowed)
				(copperpour not_allowed)
				(footprints allowed)
			)
			(placement
				(enabled no)
				(sheetname "")
			)
			(fill
				(thermal_gap 0.5)
				(thermal_bridge_width 0.5)
				(island_removal_mode 0)
			)
			(polygon
				(pts
					(xy 183.261 -146.431) (xy 183.261 -146.05) (xy 183.769 -146.05) (xy 183.769 -146.431)
				)
			)
		)
		(zone
			(layer "B.Cu")
			(hatch none 0.5)
			(connect_pads
				(clearance 0)
			)
			(min_thickness 0.25)
			(keepout
				(tracks allowed)
				(vias not_allowed)
				(pads allowed)
				(copperpour not_allowed)
				(footprints allowed)
			)
			(placement
				(enabled no)
				(sheetname "")
			)
			(fill
				(thermal_gap 0.5)
				(thermal_bridge_width 0.5)
				(island_removal_mode 0)
			)
			(polygon
				(pts
					(xy 183.261 -146.431) (xy 183.261 -146.05) (xy 183.769 -146.05) (xy 183.769 -146.431)
				)
			)
		)
	)
)
